FILE_TYPE = MULTI_PHYS_TABLE;
PART 'SCONN3_D53458001'
{==========================================================================================================================================================================================================}
:PACK_TYPE|MATERIAL   |PART_NUMBER      = EnvComp |PART_NUMBER   |JEDEC_TYPE          |CLASS  |DESCRIPTION                                              |HEIGHT      |COMPONENT_TYPE    |LPID    | SPEED_URL | Status |RPL| AML | Bus_Unit | Days;
{==========================================================================================================================================================================================================}
'SM'      | 'CONN'    | 'D53458-001'(!) = ''      | 'D53458-001' | 'SCONN3_D53458001' | 'IO'  | '(USE SYM 1)CONN,HDR,VERT,1X3,0.50CTR,FTR-103-02-S->'   | '0.250 IN' | 'SMTCONN'        | '2165' | 'http://speed.intel.com:8081/speed/module/pdm/item/pdm_item_detail_direct.asp?item_cde=D53458-001&item_rev=01&url_param=unused' | '' | '' | '' | '' | '' 
'SM'      | 'EMPTY'   | 'D53458-001'(!) = ''      | 'D53458-001' | 'SCONN3_D53458001' | 'IO'  | '(USE SYM 1)CONN,HDR,VERT,1X3,0.50CTR,FTR-103-02-S->'   | '0.250 IN' | 'SMTCONN'        | '2165' | 'http://speed.intel.com:8081/speed/module/pdm/item/pdm_item_detail_direct.asp?item_cde=D53458-001&item_rev=01&url_param=unused' | '' | '' | '' | '' | '' 
'SM1'     | 'CONN'    | 'D53458-001'(!) = ''      | 'D53458-001' | 'SCONN3_D53458001' | 'IO'  | '(USE SYM 2)CONN,HDR,VERT,1X3,0.50CTR,FTR-103-02-S->'   | '0.250 IN' | 'SMTCONN'        | '2165' | 'http://speed.intel.com:8081/speed/module/pdm/item/pdm_item_detail_direct.asp?item_cde=D53458-001&item_rev=01&url_param=unused' | '' | '' | '' | '' | '' 
'SM1'     | 'EMPTY'   | 'D53458-001'(!) = ''      | 'D53458-001' | 'SCONN3_D53458001' | 'IO'  | '(USE SYM 2)CONN,HDR,VERT,1X3,0.50CTR,FTR-103-02-S->'   | '0.250 IN' | 'SMTCONN'        | '2165' | 'http://speed.intel.com:8081/speed/module/pdm/item/pdm_item_detail_direct.asp?item_cde=D53458-001&item_rev=01&url_param=unused' | '' | '' | '' | '' | '' 
END_PART
END.
